FILE_TYPE = CONNECTIVITY;
{Allegro Design Entry HDL 17.4-2019 S026 (4007227) 1/17/2022}
"PAGE_NUMBER" = 105;
0"NC";
1"GND\g";
2"GND\g";
3"P3V3\g";
4"M_I_CPU1_SA_CB<7:0>";
5"M_I_CPU1_SB_CB<7:0>";
6"M_I_CPU1_SA_CA<6:0>";
7"M_I_CPU1_SB_CA<6:0>";
8"M_I_CPU1_SA_DQ<31:0>";
9"M_I_CPU1_SB_DQ<31:0>";
10"M_I_CPU1_SA_DQS_DN<9:0>";
11"M_I_CPU1_SA_DQS_DP<9:0>";
12"M_I_CPU1_SB_DQS_DP<9:0>";
13"M_I_CPU1_SB_DQS_DN<9:0>";
14"M_I_CPU1_SB_CB<2>";
15"M_I_CPU1_ALERT_N";
16"GND\g";
17"GND\g";
18"GND\g";
19"P12V_MEM_CPU1\g";
20"M_I_CPU1_RESET_N";
21"M_I_CPU1_SA_CB<1>";
22"M_I_CPU1_SA_CB<2>";
23"M_I_CPU1_SA_CB<3>";
24"M_I_CPU1_SB_CB<5>";
25"M_I_CPU1_SB_CB<6>";
26"M_I_CPU1_SA_CB<0>";
27"M_I_CPU1_SA_CB<6>";
28"M_I_CPU1_SA_CB<7>";
29"M_I_CPU1_CLK_DP<0>";
30"PWRGD_CHI_CPU1_DIMM";
31"PWRGD_CHGL_CPU1";
32"M_I_CPU1_SA_RSP<0>";
33"M_I_CPU1_SB_RSP<0>";
34"PD_CHI_CPU1_DIMM_SAA";
35"M_I_CPU1_SB_DQS_DP<9>";
36"M_I_CPU1_SB_DQS_DN<9>";
37"M_I_CPU1_SA_DQS_DP<9>";
38"M_I_CPU1_SA_DQS_DN<9>";
39"M_I_CPU1_SA_DQS_DP<8>";
40"M_I_CPU1_SA_DQS_DN<8>";
41"M_I_CPU1_SB_DQS_DN<7>";
42"M_I_CPU1_SA_DQS_DP<7>";
43"M_I_CPU1_SB_DQS_DP<6>";
44"M_I_CPU1_SB_DQS_DN<6>";
45"M_I_CPU1_SA_DQS_DN<6>";
46"M_I_CPU1_SB_DQS_DP<5>";
47"M_I_CPU1_SB_DQS_DN<5>";
48"M_I_CPU1_SA_DQS_DP<5>";
49"M_I_CPU1_SA_DQS_DN<5>";
50"M_I_CPU1_SB_DQS_DP<4>";
51"M_I_CPU1_SB_DQS_DN<4>";
52"M_I_CPU1_SA_DQS_DP<4>";
53"M_I_CPU1_SA_DQS_DN<4>";
54"M_I_CPU1_SB_DQS_DP<3>";
55"M_I_CPU1_SB_DQS_DN<3>";
56"M_I_CPU1_SA_DQS_DP<3>";
57"M_I_CPU1_SA_DQS_DN<3>";
58"M_I_CPU1_SB_DQS_DP<2>";
59"M_I_CPU1_SB_DQS_DN<2>";
60"M_I_CPU1_SA_DQS_DP<2>";
61"M_I_CPU1_SA_DQS_DN<2>";
62"M_I_CPU1_SB_DQS_DP<1>";
63"M_I_CPU1_SB_DQS_DN<1>";
64"M_I_CPU1_SA_DQS_DP<1>";
65"M_I_CPU1_SA_DQS_DN<1>";
66"M_I_CPU1_SB_DQS_DP<0>";
67"M_I_CPU1_SB_DQS_DN<0>";
68"M_I_CPU1_SA_DQS_DP<0>";
69"M_I_CPU1_SA_DQS_DN<0>";
70"M_I_CPU1_SB_DQS_DP<7>";
71"M_I_CPU1_SB_DQS_DN<8>";
72"M_I_CPU1_SB_DQS_DP<8>";
73"M_I_CPU1_SA_DQS_DP<6>";
74"M_I_CPU1_SA_DQS_DN<7>";
75"M_I_CPU1_SA_DQ<31>";
76"M_I_CPU1_SB_PAR";
77"M_I_CPU1_SA_PAR";
78"M_I_CPU1_SB_DQ<0>";
79"M_I_CPU1_SB_DQ<1>";
80"M_I_CPU1_SB_DQ<2>";
81"M_I_CPU1_SB_DQ<3>";
82"M_I_CPU1_SB_DQ<4>";
83"M_I_CPU1_SB_DQ<5>";
84"M_I_CPU1_SB_DQ<6>";
85"M_I_CPU1_SB_DQ<7>";
86"M_I_CPU1_SB_DQ<8>";
87"M_I_CPU1_SB_DQ<9>";
88"M_I_CPU1_SB_DQ<10>";
89"M_I_CPU1_SB_DQ<11>";
90"M_I_CPU1_SB_DQ<12>";
91"M_I_CPU1_SB_DQ<13>";
92"M_I_CPU1_SB_DQ<14>";
93"M_I_CPU1_SB_DQ<15>";
94"M_I_CPU1_SB_DQ<16>";
95"M_I_CPU1_SB_DQ<17>";
96"M_I_CPU1_SB_DQ<18>";
97"M_I_CPU1_SB_DQ<19>";
98"M_I_CPU1_SB_DQ<20>";
99"M_I_CPU1_SB_DQ<21>";
100"M_I_CPU1_SB_DQ<22>";
101"M_I_CPU1_SB_DQ<23>";
102"M_I_CPU1_SB_DQ<24>";
103"M_I_CPU1_SB_DQ<25>";
104"M_I_CPU1_SB_DQ<26>";
105"M_I_CPU1_SB_DQ<27>";
106"M_I_CPU1_SB_DQ<28>";
107"M_I_CPU1_SB_DQ<29>";
108"M_I_CPU1_SB_DQ<30>";
109"M_I_CPU1_SB_DQ<31>";
110"M_I_CPU1_SA_DQ<0>";
111"M_I_CPU1_SA_DQ<1>";
112"M_I_CPU1_SA_DQ<2>";
113"M_I_CPU1_SA_DQ<3>";
114"M_I_CPU1_SA_DQ<4>";
115"M_I_CPU1_SA_DQ<5>";
116"M_I_CPU1_SA_DQ<6>";
117"M_I_CPU1_SA_DQ<7>";
118"M_I_CPU1_SA_DQ<8>";
119"M_I_CPU1_SA_DQ<9>";
120"M_I_CPU1_SA_DQ<10>";
121"M_I_CPU1_SA_DQ<11>";
122"M_I_CPU1_SA_DQ<12>";
123"M_I_CPU1_SA_DQ<13>";
124"M_I_CPU1_SA_DQ<14>";
125"M_I_CPU1_SA_DQ<15>";
126"M_I_CPU1_SA_DQ<16>";
127"M_I_CPU1_SA_DQ<17>";
128"M_I_CPU1_SA_DQ<18>";
129"M_I_CPU1_SA_DQ<19>";
130"M_I_CPU1_SA_DQ<20>";
131"M_I_CPU1_SA_DQ<21>";
132"M_I_CPU1_SA_DQ<22>";
133"M_I_CPU1_SA_DQ<23>";
134"M_I_CPU1_SA_DQ<24>";
135"M_I_CPU1_SA_DQ<25>";
136"M_I_CPU1_SA_DQ<26>";
137"M_I_CPU1_SA_DQ<27>";
138"M_I_CPU1_SA_DQ<28>";
139"M_I_CPU1_SA_DQ<29>";
140"M_I_CPU1_SA_DQ<30>";
141"M_I_CPU1_SB_CS_N<1>";
142"M_I_CPU1_SA_CS_N<1>";
143"M_I_CPU1_SB_CS_N<0>";
144"M_I_CPU1_SA_CS_N<0>";
145"M_I_CPU1_CLK_DN<0>";
146"M_I_CPU1_SB_CB<0>";
147"M_I_CPU1_SB_CB<1>";
148"M_I_CPU1_SB_CB<3>";
149"M_I_CPU1_SB_CB<4>";
150"M_I_CPU1_SA_CB<5>";
151"M_I_CPU1_SB_CA<6>";
152"M_I_CPU1_SA_CA<6>";
153"M_I_CPU1_SB_CA<5>";
154"M_I_CPU1_SA_CA<5>";
155"M_I_CPU1_SB_CA<4>";
156"M_I_CPU1_SA_CA<4>";
157"M_I_CPU1_SB_CA<3>";
158"M_I_CPU1_SA_CA<3>";
159"M_I_CPU1_SB_CA<2>";
160"M_I_CPU1_SA_CA<2>";
161"M_I_CPU1_SB_CA<1>";
162"M_I_CPU1_SA_CA<1>";
163"M_I_CPU1_SB_CA<0>";
164"M_I_CPU1_SA_CA<0>";
165"M_I_CPU1_SB_CB<7>";
166"M_I_CPU1_SA_CB<4>";
167"I3C_SPD_DDRI_CPU1_SDA";
168"I3C_SPD_DDRI_CPU1_SCL";
169"PD_CHI_CPU1_DIMM_SAA";
170"P3V3_AUX\g";
171"I3C_SPD_DDRGL_CPU1_SDA";
172"I3C_SPD_DDRGL_CPU1_SCL";
%"TAP"
"1","(-5975,4150)","0","mstr_standard","I100";
;
CDS_LIB"mstr_standard"
BODY_TYPE"PLUMBING"
HDL_TAP"TRUE";
"B \NAC \NWC"8;
"S \NAC"
BN"7"117;
%"TAP"
"1","(-5975,4300)","0","mstr_standard","I101";
;
CDS_LIB"mstr_standard"
BODY_TYPE"PLUMBING"
HDL_TAP"TRUE";
"B \NAC \NWC"8;
"S \NAC"
BN"10"120;
%"TAP"
"1","(-5975,4250)","0","mstr_standard","I102";
;
CDS_LIB"mstr_standard"
BODY_TYPE"PLUMBING"
HDL_TAP"TRUE";
"B \NAC \NWC"8;
"S \NAC"
BN"9"119;
%"TAP"
"1","(-5975,4200)","0","mstr_standard","I103";
;
CDS_LIB"mstr_standard"
BODY_TYPE"PLUMBING"
HDL_TAP"TRUE";
"B \NAC \NWC"8;
"S \NAC"
BN"8"118;
%"TAP"
"1","(-5975,4350)","0","mstr_standard","I104";
;
CDS_LIB"mstr_standard"
BODY_TYPE"PLUMBING"
HDL_TAP"TRUE";
"B \NAC \NWC"8;
"S \NAC"
BN"11"121;
%"TAP"
"1","(-5975,4400)","0","mstr_standard","I105";
;
CDS_LIB"mstr_standard"
BODY_TYPE"PLUMBING"
HDL_TAP"TRUE";
"B \NAC \NWC"8;
"S \NAC"
BN"12"122;
%"TAP"
"1","(-5975,4450)","0","mstr_standard","I106";
;
CDS_LIB"mstr_standard"
BODY_TYPE"PLUMBING"
HDL_TAP"TRUE";
"B \NAC \NWC"8;
"S \NAC"
BN"13"123;
%"TAP"
"1","(-5975,4500)","0","mstr_standard","I107";
;
CDS_LIB"mstr_standard"
BODY_TYPE"PLUMBING"
HDL_TAP"TRUE";
"B \NAC \NWC"8;
"S \NAC"
BN"14"124;
%"TAP"
"1","(-5975,4550)","0","mstr_standard","I108";
;
CDS_LIB"mstr_standard"
BODY_TYPE"PLUMBING"
HDL_TAP"TRUE";
"B \NAC \NWC"8;
"S \NAC"
BN"15"125;
%"TAP"
"1","(-5975,4650)","0","mstr_standard","I109";
;
CDS_LIB"mstr_standard"
BODY_TYPE"PLUMBING"
HDL_TAP"TRUE";
"B \NAC \NWC"8;
"S \NAC"
BN"17"127;
%"TAP"
"1","(-5975,4600)","0","mstr_standard","I110";
;
CDS_LIB"mstr_standard"
BODY_TYPE"PLUMBING"
HDL_TAP"TRUE";
"B \NAC \NWC"8;
"S \NAC"
BN"16"126;
%"TAP"
"1","(-5975,4800)","0","mstr_standard","I111";
;
CDS_LIB"mstr_standard"
BODY_TYPE"PLUMBING"
HDL_TAP"TRUE";
"B \NAC \NWC"8;
"S \NAC"
BN"20"130;
%"TAP"
"1","(-5975,4750)","0","mstr_standard","I112";
;
CDS_LIB"mstr_standard"
BODY_TYPE"PLUMBING"
HDL_TAP"TRUE";
"B \NAC \NWC"8;
"S \NAC"
BN"19"129;
%"TAP"
"1","(-5975,4700)","0","mstr_standard","I113";
;
CDS_LIB"mstr_standard"
BODY_TYPE"PLUMBING"
HDL_TAP"TRUE";
"B \NAC \NWC"8;
"S \NAC"
BN"18"128;
%"TAP"
"1","(-5975,4900)","0","mstr_standard","I114";
;
CDS_LIB"mstr_standard"
BODY_TYPE"PLUMBING"
HDL_TAP"TRUE";
"B \NAC \NWC"8;
"S \NAC"
BN"22"132;
%"TAP"
"1","(-5975,4850)","0","mstr_standard","I115";
;
CDS_LIB"mstr_standard"
BODY_TYPE"PLUMBING"
HDL_TAP"TRUE";
"B \NAC \NWC"8;
"S \NAC"
BN"21"131;
%"TAP"
"1","(-5975,5050)","0","mstr_standard","I116";
;
CDS_LIB"mstr_standard"
BODY_TYPE"PLUMBING"
HDL_TAP"TRUE";
"B \NAC \NWC"8;
"S \NAC"
BN"25"135;
%"TAP"
"1","(-5975,5000)","0","mstr_standard","I117";
;
CDS_LIB"mstr_standard"
BODY_TYPE"PLUMBING"
HDL_TAP"TRUE";
"B \NAC \NWC"8;
"S \NAC"
BN"24"134;
%"TAP"
"1","(-5975,4950)","0","mstr_standard","I118";
;
CDS_LIB"mstr_standard"
BODY_TYPE"PLUMBING"
HDL_TAP"TRUE";
"B \NAC \NWC"8;
"S \NAC"
BN"23"133;
%"TAP"
"1","(-5975,5150)","0","mstr_standard","I119";
;
CDS_LIB"mstr_standard"
BODY_TYPE"PLUMBING"
HDL_TAP"TRUE";
"B \NAC \NWC"8;
"S \NAC"
BN"27"137;
%"TAP"
"1","(-5975,5200)","0","mstr_standard","I120";
;
CDS_LIB"mstr_standard"
BODY_TYPE"PLUMBING"
HDL_TAP"TRUE";
"B \NAC \NWC"8;
"S \NAC"
BN"28"138;
%"TAP"
"1","(-5975,5100)","0","mstr_standard","I121";
;
CDS_LIB"mstr_standard"
BODY_TYPE"PLUMBING"
HDL_TAP"TRUE";
"B \NAC \NWC"8;
"S \NAC"
BN"26"136;
%"TAP"
"1","(-5975,5300)","0","mstr_standard","I122";
;
CDS_LIB"mstr_standard"
BODY_TYPE"PLUMBING"
HDL_TAP"TRUE";
"B \NAC \NWC"8;
"S \NAC"
BN"30"140;
%"TAP"
"1","(-5975,5250)","0","mstr_standard","I123";
;
CDS_LIB"mstr_standard"
BODY_TYPE"PLUMBING"
HDL_TAP"TRUE";
"B \NAC \NWC"8;
"S \NAC"
BN"29"139;
%"TAP"
"1","(-5975,5350)","0","mstr_standard","I124";
;
CDS_LIB"mstr_standard"
BODY_TYPE"PLUMBING"
HDL_TAP"TRUE";
"B \NAC \NWC"8;
"S \NAC"
BN"31"75;
%"GND"
"1","(-6375,925)","0","mstr_symbols","I127";
;
SIZE"1B"
CDS_LIB"mstr_symbols"
BOM_COST"MEM"
VOLTAGE"0.0"
BODY_TYPE"PLUMBING"
HDL_POWER"GND";
"A\NAC"1;
%"Q_RES"
"2","(-6375,1150)","0","pure_quanta","I128";
;
LOCATION"R775"
$SEC"1"
CDS_SEC"1"
PACK_TYPE"0402LF"
VALUE"23.2K"
TOLERANCE"1%"
MATERIAL"CHIP"
WATTAGE"1/16W"
CDS_LIB"pure_quanta"
PART_NUMBER"CS32322FB03";
"A"
$PN"1"34;
"B"
$PN"2"1;
%"GND"
"1","(-2125,1825)","0","mstr_symbols","I140";
;
SIZE"1B"
CDS_LIB"mstr_symbols"
VOLTAGE"0.0"
BODY_TYPE"PLUMBING"
HDL_POWER"GND";
"A\NAC"16;
%"GND"
"1","(-325,1600)","0","mstr_symbols","I141";
;
SIZE"1B"
CDS_LIB"mstr_symbols"
VOLTAGE"0.0"
BODY_TYPE"PLUMBING"
HDL_POWER"GND";
"A\NAC"17;
%"SCONN288_DDR506112002KQ"
"3","(-1225,3600)","0","pure_quanta","I176";
;
LOCATION"J100"
$SEC"3"
CDS_SEC"3"
PART_TYPE"SMLF"
MATERIAL"IO"
VALUE"SCONN288_DDR506112002KQ"
CDS_LMAN_SYM_OUTLINE"-450,1800,450,-1750"
NEEDS_NO_SIZE"TRUE"
CDS_LIB"pure_quanta"
PART_NUMBER"DFHST8FS479";
"G3"
$PN"G3"17;
"G2"
$PN"G2"17;
"G1"
$PN"G1"17;
"VSS62"
$PN"141"17;
"VSS61"
$PN"139"17;
"VSS60"
$PN"136"17;
"VSS58"
$PN"132"17;
"VSS104"
$PN"240"16;
"VSS102"
$PN"235"16;
"VSS100"
$PN"230"16;
"VIN_BULK2"
$PN"146"19;
"VIN_BULK1"
$PN"145"19;
"VIN_BULK0"
$PN"1"19;
"VSS126"
$PN"288"16;
"VSS125"
$PN"286"16;
"VSS124"
$PN"284"16;
"VSS123"
$PN"281"16;
"VSS122"
$PN"279"16;
"VSS121"
$PN"277"16;
"VSS120"
$PN"275"16;
"VSS119"
$PN"273"16;
"VSS118"
$PN"270"16;
"VSS117"
$PN"268"16;
"VSS116"
$PN"266"16;
"VSS115"
$PN"264"16;
"VSS114"
$PN"262"16;
"VSS113"
$PN"259"16;
"VSS112"
$PN"257"16;
"VSS111"
$PN"255"16;
"VSS110"
$PN"253"16;
"VSS109"
$PN"251"16;
"VSS108"
$PN"248"16;
"VSS107"
$PN"246"16;
"VSS106"
$PN"244"16;
"VSS105"
$PN"242"16;
"VSS103"
$PN"237"16;
"VSS101"
$PN"233"16;
"VSS99"
$PN"228"16;
"VSS98"
$PN"226"16;
"VSS97"
$PN"224"16;
"VSS96"
$PN"222"16;
"VSS95"
$PN"219"16;
"VSS94"
$PN"216"16;
"VSS93"
$PN"214"16;
"VSS92"
$PN"212"16;
"VSS91"
$PN"210"16;
"VSS90"
$PN"208"16;
"VSS89"
$PN"206"16;
"VSS88"
$PN"204"16;
"VSS87"
$PN"202"16;
"VSS86"
$PN"199"16;
"VSS85"
$PN"197"16;
"VSS84"
$PN"195"16;
"VSS83"
$PN"193"16;
"VSS82"
$PN"191"16;
"VSS81"
$PN"188"16;
"VSS80"
$PN"186"16;
"VSS79"
$PN"184"16;
"VSS78"
$PN"182"16;
"VSS77"
$PN"180"16;
"VSS76"
$PN"177"16;
"VSS75"
$PN"175"16;
"VSS74"
$PN"173"16;
"VSS73"
$PN"171"16;
"VSS72"
$PN"169"16;
"VSS71"
$PN"166"16;
"VSS70"
$PN"164"16;
"VSS69"
$PN"162"16;
"VSS68"
$PN"160"16;
"VSS67"
$PN"158"16;
"VSS66"
$PN"155"16;
"VSS65"
$PN"153"16;
"VSS64"
$PN"151"16;
"VSS63"
$PN"143"17;
"VSS59"
$PN"134"17;
"VSS57"
$PN"130"17;
"VSS56"
$PN"128"17;
"VSS55"
$PN"125"17;
"VSS54"
$PN"123"17;
"VSS53"
$PN"121"17;
"VSS52"
$PN"119"17;
"VSS51"
$PN"117"17;
"VSS50"
$PN"114"17;
"VSS49"
$PN"112"17;
"VSS48"
$PN"110"17;
"VSS47"
$PN"108"17;
"VSS46"
$PN"106"17;
"VSS45"
$PN"103"17;
"VSS44"
$PN"101"17;
"VSS43"
$PN"99"17;
"VSS42"
$PN"97"17;
"VSS41"
$PN"95"17;
"VSS40"
$PN"92"17;
"VSS39"
$PN"90"17;
"VSS38"
$PN"88"17;
"VSS37"
$PN"85"17;
"VSS36"
$PN"83"17;
"VSS35"
$PN"81"17;
"VSS34"
$PN"79"17;
"VSS33"
$PN"77"17;
"VSS32"
$PN"75"17;
"VSS31"
$PN"73"17;
"VSS30"
$PN"71"17;
"VSS29"
$PN"69"17;
"VSS28"
$PN"67"17;
"VSS27"
$PN"65"17;
"VSS26"
$PN"63"17;
"VSS25"
$PN"61"17;
"VSS24"
$PN"59"17;
"VSS23"
$PN"57"17;
"VSS22"
$PN"54"17;
"VSS21"
$PN"52"17;
"VSS20"
$PN"50"17;
"VSS19"
$PN"48"17;
"VSS18"
$PN"46"17;
"VSS17"
$PN"43"17;
"VSS16"
$PN"41"17;
"VSS15"
$PN"39"17;
"VSS14"
$PN"37"17;
"VSS13"
$PN"35"17;
"VSS12"
$PN"32"17;
"VSS11"
$PN"30"17;
"VSS10"
$PN"28"17;
"VSS9"
$PN"26"17;
"VSS8"
$PN"24"17;
"VSS7"
$PN"21"17;
"VSS6"
$PN"19"17;
"VSS5"
$PN"17"17;
"VSS4"
$PN"15"17;
"VSS3"
$PN"13"17;
"VSS2"
$PN"10"17;
"VSS1"
$PN"8"17;
"VSS0"
$PN"6"17;
%"Q_CAP"
"1","(-8550,3175)","2","pure_quanta","I185";
;
LOCATION"C168"
$SEC"1"
CDS_SEC"1"
TOLERANCE"10%"
MATERIAL"X7R"
VALUE"0.1UF"
VOLTAGE"25V"
PACK_TYPE"0402"
CDS_LIB"pure_quanta"
BOM_COST"MEM"
ROOM""
PART_NUMBER"CH4104K1B00";
"B"
$PN"2"2;
"A"
$PN"1"170;
%"GND"
"1","(-8550,2950)","0","mstr_symbols","I186";
;
BOM_COST"MEM"
SIZE"1B"
CDS_LIB"mstr_symbols"
VOLTAGE"0"
ROOM"MEM_EFGH_DECOUPLING_CAPS"
BODY_TYPE"PLUMBING"
HDL_POWER"GND";
"A\NAC"2;
%"Q_RES"
"1","(-8475,2100)","2","pure_quanta","I188";
;
LOCATION"R311"
$SEC"1"
CDS_SEC"1"
VALUE"1K"
TOLERANCE"1%"
CDS_LIB"pure_quanta"
BOM_COST"MEM"
WATTAGE"1/16W"
MATERIAL"CHIP"
PACK_TYPE"0402LF"
ROOM""
PART_NUMBER"CS21002FB06";
"B"
$PN"2"31;
"A"
$PN"1"30;
%"VCC_CORE"
"1","(-8350,2425)","0","mstr_symbols","I189";
;
HDL_POWER"P3V3"
CDS_LIB"mstr_symbols"
VOLTAGE"3.3"
ROOM"PVCCINFAON_CPU0_CTRL";
"A"3;
%"Q_RES"
"2","(-8350,2250)","0","pure_quanta","I190";
;
LOCATION"R112"
$SEC"1"
CDS_SEC"1"
MATERIAL"EMPTY"
WATTAGE"1/16W"
TOLERANCE"1%"
VALUE"1K"
PACK_TYPE"0402LF"
CDS_LIB"pure_quanta"
BOM_COST"MEM"
ROOM""
PART_NUMBER"CS21002FB06";
"A"
$PN"1"3;
"B"
$PN"2"30;
%"TAP"
"1","(-3250,3100)","0","mstr_standard","I191";
;
CDS_LIB"mstr_standard"
BODY_TYPE"PLUMBING"
HDL_TAP"TRUE";
"B \NAC \NWC"13;
"S \NAC"
BN"7"41;
%"TAP"
"1","(-3250,3300)","0","mstr_standard","I192";
;
CDS_LIB"mstr_standard"
BODY_TYPE"PLUMBING"
HDL_TAP"TRUE";
"B \NAC \NWC"13;
"S \NAC"
BN"9"36;
%"TAP"
"1","(-3250,3450)","0","mstr_standard","I193";
;
CDS_LIB"mstr_standard"
BODY_TYPE"PLUMBING"
HDL_TAP"TRUE";
"B \NAC \NWC"10;
"S \NAC"
BN"0"69;
%"TAP"
"1","(-3250,3550)","0","mstr_standard","I194";
;
CDS_LIB"mstr_standard"
BODY_TYPE"PLUMBING"
HDL_TAP"TRUE";
"B \NAC \NWC"10;
"S \NAC"
BN"1"65;
%"TAP"
"1","(-3450,3800)","0","mstr_standard","I195";
;
CDS_LIB"mstr_standard"
BODY_TYPE"PLUMBING"
HDL_TAP"TRUE";
"B \NAC \NWC"11;
"S \NAC"
BN"3"56;
%"TAP"
"1","(-3250,4350)","0","mstr_standard","I201";
;
CDS_LIB"mstr_standard"
BODY_TYPE"PLUMBING"
HDL_TAP"TRUE";
"B \NAC \NWC"10;
"S \NAC"
BN"9"38;
%"TAP"
"1","(-3450,4400)","0","mstr_standard","I202";
;
CDS_LIB"mstr_standard"
BODY_TYPE"PLUMBING"
HDL_TAP"TRUE";
"B \NAC \NWC"11;
"S \NAC"
BN"9"37;
%"TAP"
"1","(-3450,4300)","0","mstr_standard","I203";
;
CDS_LIB"mstr_standard"
BODY_TYPE"PLUMBING"
HDL_TAP"TRUE";
"B \NAC \NWC"11;
"S \NAC"
BN"8"39;
%"TAP"
"1","(-3250,4250)","0","mstr_standard","I204";
;
CDS_LIB"mstr_standard"
BODY_TYPE"PLUMBING"
HDL_TAP"TRUE";
"B \NAC \NWC"10;
"S \NAC"
BN"8"40;
%"TAP"
"1","(-3250,4150)","0","mstr_standard","I205";
;
CDS_LIB"mstr_standard"
BODY_TYPE"PLUMBING"
HDL_TAP"TRUE";
"B \NAC \NWC"10;
"S \NAC"
BN"7"74;
%"TAP"
"1","(-3250,4050)","0","mstr_standard","I206";
;
CDS_LIB"mstr_standard"
BODY_TYPE"PLUMBING"
HDL_TAP"TRUE";
"B \NAC \NWC"10;
"S \NAC"
BN"6"45;
%"TAP"
"1","(-3250,3950)","0","mstr_standard","I207";
;
CDS_LIB"mstr_standard"
BODY_TYPE"PLUMBING"
HDL_TAP"TRUE";
"B \NAC \NWC"10;
"S \NAC"
BN"5"49;
%"TAP"
"1","(-3250,3850)","0","mstr_standard","I208";
;
CDS_LIB"mstr_standard"
BODY_TYPE"PLUMBING"
HDL_TAP"TRUE";
"B \NAC \NWC"10;
"S \NAC"
BN"4"53;
%"TAP"
"1","(-3250,3650)","0","mstr_standard","I209";
;
CDS_LIB"mstr_standard"
BODY_TYPE"PLUMBING"
HDL_TAP"TRUE";
"B \NAC \NWC"10;
"S \NAC"
BN"2"61;
%"TAP"
"1","(-3250,3750)","0","mstr_standard","I210";
;
CDS_LIB"mstr_standard"
BODY_TYPE"PLUMBING"
HDL_TAP"TRUE";
"B \NAC \NWC"10;
"S \NAC"
BN"3"57;
%"TAP"
"1","(-3450,4200)","0","mstr_standard","I211";
;
CDS_LIB"mstr_standard"
BODY_TYPE"PLUMBING"
HDL_TAP"TRUE";
"B \NAC \NWC"11;
"S \NAC"
BN"7"42;
%"TAP"
"1","(-3450,4100)","0","mstr_standard","I212";
;
CDS_LIB"mstr_standard"
BODY_TYPE"PLUMBING"
HDL_TAP"TRUE";
"B \NAC \NWC"11;
"S \NAC"
BN"6"73;
%"TAP"
"1","(-3450,3900)","0","mstr_standard","I213";
;
CDS_LIB"mstr_standard"
BODY_TYPE"PLUMBING"
HDL_TAP"TRUE";
"B \NAC \NWC"11;
"S \NAC"
BN"4"52;
%"TAP"
"1","(-3450,4000)","0","mstr_standard","I214";
;
CDS_LIB"mstr_standard"
BODY_TYPE"PLUMBING"
HDL_TAP"TRUE";
"B \NAC \NWC"11;
"S \NAC"
BN"5"48;
%"TAP"
"1","(-3450,3700)","0","mstr_standard","I215";
;
CDS_LIB"mstr_standard"
BODY_TYPE"PLUMBING"
HDL_TAP"TRUE";
"B \NAC \NWC"11;
"S \NAC"
BN"2"60;
%"TAP"
"1","(-3450,3600)","0","mstr_standard","I216";
;
CDS_LIB"mstr_standard"
BODY_TYPE"PLUMBING"
HDL_TAP"TRUE";
"B \NAC \NWC"11;
"S \NAC"
BN"1"64;
%"TAP"
"1","(-3450,3500)","0","mstr_standard","I217";
;
CDS_LIB"mstr_standard"
BODY_TYPE"PLUMBING"
HDL_TAP"TRUE";
"B \NAC \NWC"11;
"S \NAC"
BN"0"68;
%"TAP"
"1","(-3450,3250)","0","mstr_standard","I218";
;
CDS_LIB"mstr_standard"
BODY_TYPE"PLUMBING"
HDL_TAP"TRUE";
"B \NAC \NWC"12;
"S \NAC"
BN"8"72;
%"TAP"
"1","(-3450,3350)","0","mstr_standard","I219";
;
CDS_LIB"mstr_standard"
BODY_TYPE"PLUMBING"
HDL_TAP"TRUE";
"B \NAC \NWC"12;
"S \NAC"
BN"9"35;
%"SCONN288_DDR506112002KQ"
"1","(-6825,3600)","0","pure_quanta","I22";
;
LOCATION"J100"
$SEC"1"
CDS_SEC"1"
PART_TYPE"SMLF"
MATERIAL"IO"
VALUE"SCONN288_DDR506112002KQ"
CDS_LMAN_SYM_OUTLINE"-450,1900,450,-1850"
NEEDS_NO_SIZE"TRUE"
CDS_LIB"pure_quanta"
PART_NUMBER"DFHST8FS479";
"PWR_GOOD||FAIL_N"
$PN"147"30;
"DQ31_A"
$PN"194"75;
"CB7_A"
$PN"205"28;
"CB4_A"
$PN"58"166;
"CB1_A"
$PN"53"21;
"CB7_B"
$PN"236"165;
"ALERT_N \B"
$PN"62"15;
"CA0_A"
$PN"66"164;
"CA0_B"
$PN"76"163;
"CA1_A"
$PN"211"162;
"CA1_B"
$PN"221"161;
"CA2_A"
$PN"68"160;
"CA2_B"
$PN"78"159;
"CA3_A"
$PN"213"158;
"CA3_B"
$PN"223"157;
"CA4_A"
$PN"70"156;
"CA4_B"
$PN"80"155;
"CA5_A"
$PN"215"154;
"CA5_B"
$PN"225"153;
"CA6_A"
$PN"72"152;
"CA6_B"
$PN"82"151;
"CB6_A"
$PN"203"27;
"CB5_A"
$PN"60"150;
"CB3_A"
$PN"198"23;
"CB2_A"
$PN"196"22;
"CB0_A"
$PN"51"26;
"CB6_B"
$PN"234"25;
"CB5_B"
$PN"91"24;
"CB4_B"
$PN"89"149;
"CB3_B"
$PN"243"148;
"CB2_B"
$PN"241"14;
"CB1_B"
$PN"98"147;
"CB0_B"
$PN"96"146;
"CK_C \B"
$PN"218"145;
"CK_T"
$PN"217"29;
"CS0_A_N"
$PN"64"144;
"CS0_B_N"
$PN"84"143;
"CS1_A_N"
$PN"209"142;
"CS1_B_N"
$PN"229"141;
"DQ30_A"
$PN"192"140;
"DQ29_A"
$PN"49"139;
"DQ28_A"
$PN"47"138;
"DQ27_A"
$PN"187"137;
"DQ26_A"
$PN"185"136;
"DQ25_A"
$PN"42"135;
"DQ24_A"
$PN"40"134;
"DQ23_A"
$PN"183"133;
"DQ22_A"
$PN"181"132;
"DQ21_A"
$PN"38"131;
"DQ20_A"
$PN"36"130;
"DQ19_A"
$PN"176"129;
"DQ18_A"
$PN"174"128;
"DQ17_A"
$PN"31"127;
"DQ16_A"
$PN"29"126;
"DQ15_A"
$PN"172"125;
"DQ14_A"
$PN"170"124;
"DQ13_A"
$PN"27"123;
"DQ12_A"
$PN"25"122;
"DQ11_A"
$PN"165"121;
"DQ10_A"
$PN"163"120;
"DQ9_A"
$PN"20"119;
"DQ8_A"
$PN"18"118;
"DQ7_A"
$PN"161"117;
"DQ6_A"
$PN"159"116;
"DQ5_A"
$PN"16"115;
"DQ4_A"
$PN"14"114;
"DQ3_A"
$PN"154"113;
"DQ2_A"
$PN"152"112;
"DQ1_A"
$PN"9"111;
"DQ0_A"
$PN"7"110;
"DQ31_B"
$PN"287"109;
"DQ30_B"
$PN"285"108;
"DQ29_B"
$PN"142"107;
"DQ28_B"
$PN"140"106;
"DQ27_B"
$PN"280"105;
"DQ26_B"
$PN"278"104;
"DQ25_B"
$PN"135"103;
"DQ24_B"
$PN"133"102;
"DQ23_B"
$PN"276"101;
"DQ22_B"
$PN"274"100;
"DQ21_B"
$PN"131"99;
"DQ20_B"
$PN"129"98;
"DQ19_B"
$PN"269"97;
"DQ18_B"
$PN"267"96;
"DQ17_B"
$PN"124"95;
"DQ16_B"
$PN"122"94;
"DQ15_B"
$PN"265"93;
"DQ14_B"
$PN"263"92;
"DQ13_B"
$PN"120"91;
"DQ12_B"
$PN"118"90;
"DQ11_B"
$PN"258"89;
"DQ10_B"
$PN"256"88;
"DQ9_B"
$PN"113"87;
"DQ8_B"
$PN"111"86;
"DQ7_B"
$PN"254"85;
"DQ6_B"
$PN"252"84;
"DQ5_B"
$PN"109"83;
"DQ4_B"
$PN"107"82;
"DQ3_B"
$PN"247"81;
"DQ2_B"
$PN"245"80;
"DQ1_B"
$PN"102"79;
"DQ0_B"
$PN"100"78;
"HAS"
$PN"148"169;
"HSCL"
$PN"4"168;
"HSDA"
$PN"5"167;
"LBD||RSP_A_N"
$PN"86"32;
"LBS||RSP_B_N"
$PN"87"33;
"PAR_A"
$PN"74"77;
"PAR_B"
$PN"227"76;
"RESET_N \B"
$PN"207"20;
"RFU6"
$PN"232"0;
"RFU5"
$PN"231"0;
"RFU4"
$PN"220"0;
"RFU3"
$PN"150"0;
"RFU2"
$PN"149"0;
"RFU1"
$PN"144"0;
"RFU0"
$PN"2"0;
"VIN_MGMT"
$PN"3"170;
%"TAP"
"1","(-3250,3200)","0","mstr_standard","I220";
;
CDS_LIB"mstr_standard"
BODY_TYPE"PLUMBING"
HDL_TAP"TRUE";
"B \NAC \NWC"13;
"S \NAC"
BN"8"71;
%"TAP"
"1","(-3250,3000)","0","mstr_standard","I221";
;
CDS_LIB"mstr_standard"
BODY_TYPE"PLUMBING"
HDL_TAP"TRUE";
"B \NAC \NWC"13;
"S \NAC"
BN"6"44;
%"TAP"
"1","(-3250,2900)","0","mstr_standard","I222";
;
CDS_LIB"mstr_standard"
BODY_TYPE"PLUMBING"
HDL_TAP"TRUE";
"B \NAC \NWC"13;
"S \NAC"
BN"5"47;
%"TAP"
"1","(-3250,2800)","0","mstr_standard","I223";
;
CDS_LIB"mstr_standard"
BODY_TYPE"PLUMBING"
HDL_TAP"TRUE";
"B \NAC \NWC"13;
"S \NAC"
BN"4"51;
%"TAP"
"1","(-3250,2700)","0","mstr_standard","I224";
;
CDS_LIB"mstr_standard"
BODY_TYPE"PLUMBING"
HDL_TAP"TRUE";
"B \NAC \NWC"13;
"S \NAC"
BN"3"55;
%"TAP"
"1","(-3250,2600)","0","mstr_standard","I225";
;
CDS_LIB"mstr_standard"
BODY_TYPE"PLUMBING"
HDL_TAP"TRUE";
"B \NAC \NWC"13;
"S \NAC"
BN"2"59;
%"TAP"
"1","(-3250,2500)","0","mstr_standard","I226";
;
CDS_LIB"mstr_standard"
BODY_TYPE"PLUMBING"
HDL_TAP"TRUE";
"B \NAC \NWC"13;
"S \NAC"
BN"1"63;
%"TAP"
"1","(-3250,2400)","0","mstr_standard","I227";
;
CDS_LIB"mstr_standard"
BODY_TYPE"PLUMBING"
HDL_TAP"TRUE";
"B \NAC \NWC"13;
"S \NAC"
BN"0"67;
%"TAP"
"1","(-3450,3150)","0","mstr_standard","I228";
;
CDS_LIB"mstr_standard"
BODY_TYPE"PLUMBING"
HDL_TAP"TRUE";
"B \NAC \NWC"12;
"S \NAC"
BN"7"70;
%"TAP"
"1","(-3450,3050)","0","mstr_standard","I229";
;
CDS_LIB"mstr_standard"
BODY_TYPE"PLUMBING"
HDL_TAP"TRUE";
"B \NAC \NWC"12;
"S \NAC"
BN"6"43;
%"TAP"
"1","(-7675,3150)","2","mstr_standard","I23";
;
CDS_LIB"mstr_standard"
BODY_TYPE"PLUMBING"
HDL_TAP"TRUE";
"B \NAC \NWC"5;
"S \NAC"
BN"0"146;
%"TAP"
"1","(-3450,2950)","0","mstr_standard","I230";
;
CDS_LIB"mstr_standard"
BODY_TYPE"PLUMBING"
HDL_TAP"TRUE";
"B \NAC \NWC"12;
"S \NAC"
BN"5"46;
%"TAP"
"1","(-3450,2750)","0","mstr_standard","I231";
;
CDS_LIB"mstr_standard"
BODY_TYPE"PLUMBING"
HDL_TAP"TRUE";
"B \NAC \NWC"12;
"S \NAC"
BN"3"54;
%"TAP"
"1","(-3450,2850)","0","mstr_standard","I232";
;
CDS_LIB"mstr_standard"
BODY_TYPE"PLUMBING"
HDL_TAP"TRUE";
"B \NAC \NWC"12;
"S \NAC"
BN"4"50;
%"TAP"
"1","(-3450,2650)","0","mstr_standard","I233";
;
CDS_LIB"mstr_standard"
BODY_TYPE"PLUMBING"
HDL_TAP"TRUE";
"B \NAC \NWC"12;
"S \NAC"
BN"2"58;
%"TAP"
"1","(-3450,2550)","0","mstr_standard","I234";
;
CDS_LIB"mstr_standard"
BODY_TYPE"PLUMBING"
HDL_TAP"TRUE";
"B \NAC \NWC"12;
"S \NAC"
BN"1"62;
%"TAP"
"1","(-3450,2450)","0","mstr_standard","I235";
;
CDS_LIB"mstr_standard"
BODY_TYPE"PLUMBING"
HDL_TAP"TRUE";
"B \NAC \NWC"12;
"S \NAC"
BN"0"66;
%"SCONN288_DDR506112002KQ"
"2","(-4400,3400)","0","pure_quanta","I236";
;
LOCATION"J100"
$SEC"2"
CDS_SEC"2"
MATERIAL"IO"
VALUE"SCONN288_DDR506112002KQ"
PART_TYPE"SMLF"
CDS_LMAN_SYM_OUTLINE"-600,1150,600,-1150"
NEEDS_NO_SIZE"TRUE"
CDS_LIB"pure_quanta"
PART_NUMBER"DFHST8FS479";
"DQS7_A_C||TDQS7_A_C \B"
$PN"178"74;
"DQS6_A_T||TDQS6_A_T"
$PN"168"73;
"DQS8_B_T||TDQS8_B_T"
$PN"283"72;
"DQS8_B_C||TDQS8_B_C \B"
$PN"282"71;
"DQS7_B_T||TDQS7_B_T"
$PN"272"70;
"DQS0_A_C \B"
$PN"12"69;
"DQS0_A_T"
$PN"11"68;
"DQS0_B_C \B"
$PN"105"67;
"DQS0_B_T"
$PN"104"66;
"DQS1_A_C \B"
$PN"23"65;
"DQS1_A_T"
$PN"22"64;
"DQS1_B_C \B"
$PN"116"63;
"DQS1_B_T"
$PN"115"62;
"DQS2_A_C \B"
$PN"34"61;
"DQS2_A_T"
$PN"33"60;
"DQS2_B_C \B"
$PN"127"59;
"DQS2_B_T"
$PN"126"58;
"DQS3_A_C \B"
$PN"45"57;
"DQS3_A_T"
$PN"44"56;
"DQS3_B_C \B"
$PN"138"55;
"DQS3_B_T"
$PN"137"54;
"DQS4_A_C \B"
$PN"56"53;
"DQS4_A_T"
$PN"55"52;
"DQS4_B_C \B"
$PN"238"51;
"DQS4_B_T"
$PN"239"50;
"DQS5_A_C||TDQS5_A_C||DQS5_A_T||TDQS5_A_T \B"
$PN"156"49;
"DQS5_A_T||TDQS5_A_T"
$PN"157"48;
"DQS5_B_C||TDQS5_B_C \B"
$PN"249"47;
"DQS5_B_T||TDQS5_B_T"
$PN"250"46;
"DQS6_A_C||TDQS6_A_C||DQS6_A_T||TDQS6_A_T \B"
$PN"167"45;
"DQS6_B_C||TDQS6_B_C \B"
$PN"260"44;
"DQS6_B_T||TDQS6_B_T"
$PN"261"43;
"DQS7_A_T||TDQS7_A_T"
$PN"179"42;
"DQS7_B_C||TDQS7_B_C \B"
$PN"271"41;
"DQS8_A_C||TDQS8_A_C \B"
$PN"189"40;
"DQS8_A_T||TDQS8_A_T"
$PN"190"39;
"DQS9_A_C||TDQS9_A_C \B"
$PN"200"38;
"DQS9_A_T||TDQS9_A_T"
$PN"201"37;
"DQS9_B_C||TDQS9_B_C \B"
$PN"94"36;
"DQS9_B_T||TDQS9_B_T||DBI4_B_N"
$PN"93"35;
%"GND"
"1","(-2825,5450)","0","pure_quanta_power","I237";
;
CDS_LIB"pure_quanta_power"
BOM_COST"MEM"
SIZE"1B"
ROOM"MEM_EFGH_DECOUPLING_CAPS"
HDL_POWER"GND";
"A<SIZE-1..0>\NAC"18;
%"Q_CAP"
"1","(-2825,5800)","2","pure_quanta","I238";
;
LOCATION"C534"
$SEC"1"
CDS_SEC"1"
VALUE"10UF"
PACK_TYPE"C0805"
VOLTAGE"25V"
TOLERANCE"10%"
MATERIAL"X6S"
CDS_LIB"pure_quanta"
BOM_COST"MEM"
ROOM""
PART_NUMBER"CH6104KEA00";
"B"
$PN"2"18;
"A"
$PN"1"19;
%"Q_CAP"
"1","(-2250,5800)","2","pure_quanta","I239";
;
LOCATION"C535"
$SEC"1"
CDS_SEC"1"
PACK_TYPE"C0805"
VOLTAGE"25V"
VALUE"10UF"
TOLERANCE"10%"
MATERIAL"X6S"
CDS_LIB"pure_quanta"
BOM_COST"MEM"
ROOM""
PART_NUMBER"CH6104KEA00";
"B"
$PN"2"18;
"A"
$PN"1"19;
%"TAP"
"1","(-7675,3200)","2","mstr_standard","I24";
;
CDS_LIB"mstr_standard"
BODY_TYPE"PLUMBING"
HDL_TAP"TRUE";
"B \NAC \NWC"5;
"S \NAC"
BN"1"147;
%"UNIVERSAL_POWER"
"1","(-2825,6125)","0","pure_quanta_power","I240";
;
HDL_POWER"P12V_MEM_CPU1"
CDS_LIB"pure_quanta_power";
"A"19;
%"Q_RES"
"1","(-7725,2575)","0","pure_quanta","I242";
;
LOCATION"R1588"
$SEC"1"
CDS_SEC"1"
VALUE"49.9"
CDS_LIB"pure_quanta"
TOLERANCE"1%"
WATTAGE"1/16W"
PACK_TYPE"0402LF"
MATERIAL"CHIP"
PART_NUMBER"CS04992FB07";
"B"
$PN"2"168;
"A"
$PN"1"172;
%"Q_RES"
"1","(-8100,2800)","0","pure_quanta","I243";
;
LOCATION"R1708"
$SEC"1"
CDS_SEC"1"
MATERIAL"CHIP"
PACK_TYPE"0402LF"
VALUE"10"
TOLERANCE"1%"
WATTAGE"1/16W"
CDS_LIB"pure_quanta"
PART_NUMBER"CS01002FB07";
"B"
$PN"2"167;
"A"
$PN"1"171;
%"TAP"
"1","(-7675,3250)","2","mstr_standard","I25";
;
CDS_LIB"mstr_standard"
BODY_TYPE"PLUMBING"
HDL_TAP"TRUE";
"B \NAC \NWC"5;
"S \NAC"
BN"2"14;
%"TAP"
"1","(-7675,3300)","2","mstr_standard","I26";
;
CDS_LIB"mstr_standard"
BODY_TYPE"PLUMBING"
HDL_TAP"TRUE";
"B \NAC \NWC"5;
"S \NAC"
BN"3"148;
%"TAP"
"1","(-7675,3350)","2","mstr_standard","I27";
;
CDS_LIB"mstr_standard"
BODY_TYPE"PLUMBING"
HDL_TAP"TRUE";
"B \NAC \NWC"5;
"S \NAC"
BN"4"149;
%"TAP"
"1","(-7675,3400)","2","mstr_standard","I28";
;
CDS_LIB"mstr_standard"
BODY_TYPE"PLUMBING"
HDL_TAP"TRUE";
"B \NAC \NWC"5;
"S \NAC"
BN"5"24;
%"TAP"
"1","(-7675,3450)","2","mstr_standard","I29";
;
CDS_LIB"mstr_standard"
BODY_TYPE"PLUMBING"
HDL_TAP"TRUE";
"B \NAC \NWC"5;
"S \NAC"
BN"6"25;
%"TAP"
"1","(-7675,3500)","2","mstr_standard","I30";
;
CDS_LIB"mstr_standard"
BODY_TYPE"PLUMBING"
HDL_TAP"TRUE";
"B \NAC \NWC"5;
"S \NAC"
BN"7"165;
%"TAP"
"1","(-7675,3600)","2","mstr_standard","I31";
;
CDS_LIB"mstr_standard"
BODY_TYPE"PLUMBING"
HDL_TAP"TRUE";
"B \NAC \NWC"4;
"S \NAC"
BN"0"26;
%"TAP"
"1","(-7675,3650)","2","mstr_standard","I32";
;
CDS_LIB"mstr_standard"
BODY_TYPE"PLUMBING"
HDL_TAP"TRUE";
"B \NAC \NWC"4;
"S \NAC"
BN"1"21;
%"TAP"
"1","(-7675,3750)","2","mstr_standard","I33";
;
CDS_LIB"mstr_standard"
BODY_TYPE"PLUMBING"
HDL_TAP"TRUE";
"B \NAC \NWC"4;
"S \NAC"
BN"3"23;
%"TAP"
"1","(-7675,3700)","2","mstr_standard","I34";
;
CDS_LIB"mstr_standard"
BODY_TYPE"PLUMBING"
HDL_TAP"TRUE";
"B \NAC \NWC"4;
"S \NAC"
BN"2"22;
%"TAP"
"1","(-5975,2150)","0","mstr_standard","I35";
;
CDS_LIB"mstr_standard"
BODY_TYPE"PLUMBING"
HDL_TAP"TRUE";
"B \NAC \NWC"9;
"S \NAC"
BN"0"78;
%"TAP"
"1","(-5975,2250)","0","mstr_standard","I36";
;
CDS_LIB"mstr_standard"
BODY_TYPE"PLUMBING"
HDL_TAP"TRUE";
"B \NAC \NWC"9;
"S \NAC"
BN"2"80;
%"TAP"
"1","(-5975,2200)","0","mstr_standard","I37";
;
CDS_LIB"mstr_standard"
BODY_TYPE"PLUMBING"
HDL_TAP"TRUE";
"B \NAC \NWC"9;
"S \NAC"
BN"1"79;
%"TAP"
"1","(-5975,2350)","0","mstr_standard","I38";
;
CDS_LIB"mstr_standard"
BODY_TYPE"PLUMBING"
HDL_TAP"TRUE";
"B \NAC \NWC"9;
"S \NAC"
BN"4"82;
%"TAP"
"1","(-5975,2300)","0","mstr_standard","I39";
;
CDS_LIB"mstr_standard"
BODY_TYPE"PLUMBING"
HDL_TAP"TRUE";
"B \NAC \NWC"9;
"S \NAC"
BN"3"81;
%"TAP"
"1","(-5975,2400)","0","mstr_standard","I40";
;
CDS_LIB"mstr_standard"
BODY_TYPE"PLUMBING"
HDL_TAP"TRUE";
"B \NAC \NWC"9;
"S \NAC"
BN"5"83;
%"TAP"
"1","(-5975,2450)","0","mstr_standard","I41";
;
CDS_LIB"mstr_standard"
BODY_TYPE"PLUMBING"
HDL_TAP"TRUE";
"B \NAC \NWC"9;
"S \NAC"
BN"6"84;
%"TAP"
"1","(-5975,2500)","0","mstr_standard","I42";
;
CDS_LIB"mstr_standard"
BODY_TYPE"PLUMBING"
HDL_TAP"TRUE";
"B \NAC \NWC"9;
"S \NAC"
BN"7"85;
%"TAP"
"1","(-5975,2600)","0","mstr_standard","I43";
;
CDS_LIB"mstr_standard"
BODY_TYPE"PLUMBING"
HDL_TAP"TRUE";
"B \NAC \NWC"9;
"S \NAC"
BN"9"87;
%"TAP"
"1","(-5975,2550)","0","mstr_standard","I44";
;
CDS_LIB"mstr_standard"
BODY_TYPE"PLUMBING"
HDL_TAP"TRUE";
"B \NAC \NWC"9;
"S \NAC"
BN"8"86;
%"TAP"
"1","(-5975,2650)","0","mstr_standard","I45";
;
CDS_LIB"mstr_standard"
BODY_TYPE"PLUMBING"
HDL_TAP"TRUE";
"B \NAC \NWC"9;
"S \NAC"
BN"10"88;
%"TAP"
"1","(-5975,2750)","0","mstr_standard","I46";
;
CDS_LIB"mstr_standard"
BODY_TYPE"PLUMBING"
HDL_TAP"TRUE";
"B \NAC \NWC"9;
"S \NAC"
BN"12"90;
%"TAP"
"1","(-5975,2700)","0","mstr_standard","I47";
;
CDS_LIB"mstr_standard"
BODY_TYPE"PLUMBING"
HDL_TAP"TRUE";
"B \NAC \NWC"9;
"S \NAC"
BN"11"89;
%"TAP"
"1","(-5975,2850)","0","mstr_standard","I48";
;
CDS_LIB"mstr_standard"
BODY_TYPE"PLUMBING"
HDL_TAP"TRUE";
"B \NAC \NWC"9;
"S \NAC"
BN"14"92;
%"TAP"
"1","(-5975,2800)","0","mstr_standard","I49";
;
CDS_LIB"mstr_standard"
BODY_TYPE"PLUMBING"
HDL_TAP"TRUE";
"B \NAC \NWC"9;
"S \NAC"
BN"13"91;
%"TAP"
"1","(-5975,2900)","0","mstr_standard","I50";
;
CDS_LIB"mstr_standard"
BODY_TYPE"PLUMBING"
HDL_TAP"TRUE";
"B \NAC \NWC"9;
"S \NAC"
BN"15"93;
%"TAP"
"1","(-5975,3000)","0","mstr_standard","I51";
;
CDS_LIB"mstr_standard"
BODY_TYPE"PLUMBING"
HDL_TAP"TRUE";
"B \NAC \NWC"9;
"S \NAC"
BN"17"95;
%"TAP"
"1","(-5975,2950)","0","mstr_standard","I52";
;
CDS_LIB"mstr_standard"
BODY_TYPE"PLUMBING"
HDL_TAP"TRUE";
"B \NAC \NWC"9;
"S \NAC"
BN"16"94;
%"TAP"
"1","(-5975,3150)","0","mstr_standard","I53";
;
CDS_LIB"mstr_standard"
BODY_TYPE"PLUMBING"
HDL_TAP"TRUE";
"B \NAC \NWC"9;
"S \NAC"
BN"20"98;
%"TAP"
"1","(-5975,3100)","0","mstr_standard","I54";
;
CDS_LIB"mstr_standard"
BODY_TYPE"PLUMBING"
HDL_TAP"TRUE";
"B \NAC \NWC"9;
"S \NAC"
BN"19"97;
%"TAP"
"1","(-5975,3050)","0","mstr_standard","I55";
;
CDS_LIB"mstr_standard"
BODY_TYPE"PLUMBING"
HDL_TAP"TRUE";
"B \NAC \NWC"9;
"S \NAC"
BN"18"96;
%"TAP"
"1","(-5975,3200)","0","mstr_standard","I56";
;
CDS_LIB"mstr_standard"
BODY_TYPE"PLUMBING"
HDL_TAP"TRUE";
"B \NAC \NWC"9;
"S \NAC"
BN"21"99;
%"TAP"
"1","(-5975,3250)","0","mstr_standard","I57";
;
CDS_LIB"mstr_standard"
BODY_TYPE"PLUMBING"
HDL_TAP"TRUE";
"B \NAC \NWC"9;
"S \NAC"
BN"22"100;
%"TAP"
"1","(-5975,3400)","0","mstr_standard","I58";
;
CDS_LIB"mstr_standard"
BODY_TYPE"PLUMBING"
HDL_TAP"TRUE";
"B \NAC \NWC"9;
"S \NAC"
BN"25"103;
%"TAP"
"1","(-5975,3350)","0","mstr_standard","I59";
;
CDS_LIB"mstr_standard"
BODY_TYPE"PLUMBING"
HDL_TAP"TRUE";
"B \NAC \NWC"9;
"S \NAC"
BN"24"102;
%"TAP"
"1","(-5975,3300)","0","mstr_standard","I60";
;
CDS_LIB"mstr_standard"
BODY_TYPE"PLUMBING"
HDL_TAP"TRUE";
"B \NAC \NWC"9;
"S \NAC"
BN"23"101;
%"TAP"
"1","(-5975,3450)","0","mstr_standard","I61";
;
CDS_LIB"mstr_standard"
BODY_TYPE"PLUMBING"
HDL_TAP"TRUE";
"B \NAC \NWC"9;
"S \NAC"
BN"26"104;
%"TAP"
"1","(-5975,3500)","0","mstr_standard","I62";
;
CDS_LIB"mstr_standard"
BODY_TYPE"PLUMBING"
HDL_TAP"TRUE";
"B \NAC \NWC"9;
"S \NAC"
BN"27"105;
%"TAP"
"1","(-5975,3650)","0","mstr_standard","I63";
;
CDS_LIB"mstr_standard"
BODY_TYPE"PLUMBING"
HDL_TAP"TRUE";
"B \NAC \NWC"9;
"S \NAC"
BN"30"108;
%"TAP"
"1","(-5975,3600)","0","mstr_standard","I64";
;
CDS_LIB"mstr_standard"
BODY_TYPE"PLUMBING"
HDL_TAP"TRUE";
"B \NAC \NWC"9;
"S \NAC"
BN"29"107;
%"TAP"
"1","(-5975,3550)","0","mstr_standard","I65";
;
CDS_LIB"mstr_standard"
BODY_TYPE"PLUMBING"
HDL_TAP"TRUE";
"B \NAC \NWC"9;
"S \NAC"
BN"28"106;
%"TAP"
"1","(-5975,3700)","0","mstr_standard","I66";
;
CDS_LIB"mstr_standard"
BODY_TYPE"PLUMBING"
HDL_TAP"TRUE";
"B \NAC \NWC"9;
"S \NAC"
BN"31"109;
%"TAP"
"1","(-7675,3800)","2","mstr_standard","I75";
;
CDS_LIB"mstr_standard"
BODY_TYPE"PLUMBING"
HDL_TAP"TRUE";
"B \NAC \NWC"4;
"S \NAC"
BN"4"166;
%"TAP"
"1","(-7675,3850)","2","mstr_standard","I76";
;
CDS_LIB"mstr_standard"
BODY_TYPE"PLUMBING"
HDL_TAP"TRUE";
"B \NAC \NWC"4;
"S \NAC"
BN"5"150;
%"TAP"
"1","(-7675,3900)","2","mstr_standard","I77";
;
CDS_LIB"mstr_standard"
BODY_TYPE"PLUMBING"
HDL_TAP"TRUE";
"B \NAC \NWC"4;
"S \NAC"
BN"6"27;
%"TAP"
"1","(-7675,3950)","2","mstr_standard","I78";
;
CDS_LIB"mstr_standard"
BODY_TYPE"PLUMBING"
HDL_TAP"TRUE";
"B \NAC \NWC"4;
"S \NAC"
BN"7"28;
%"TAP"
"1","(-7675,4650)","2","mstr_standard","I79";
;
CDS_LIB"mstr_standard"
BODY_TYPE"PLUMBING"
HDL_TAP"TRUE";
"B \NAC \NWC"7;
"S \NAC"
BN"0"163;
%"TAP"
"1","(-7675,4700)","2","mstr_standard","I80";
;
CDS_LIB"mstr_standard"
BODY_TYPE"PLUMBING"
HDL_TAP"TRUE";
"B \NAC \NWC"7;
"S \NAC"
BN"1"161;
%"TAP"
"1","(-7675,4750)","2","mstr_standard","I81";
;
CDS_LIB"mstr_standard"
BODY_TYPE"PLUMBING"
HDL_TAP"TRUE";
"B \NAC \NWC"7;
"S \NAC"
BN"2"159;
%"TAP"
"1","(-7675,4800)","2","mstr_standard","I82";
;
CDS_LIB"mstr_standard"
BODY_TYPE"PLUMBING"
HDL_TAP"TRUE";
"B \NAC \NWC"7;
"S \NAC"
BN"3"157;
%"TAP"
"1","(-7675,4850)","2","mstr_standard","I83";
;
CDS_LIB"mstr_standard"
BODY_TYPE"PLUMBING"
HDL_TAP"TRUE";
"B \NAC \NWC"7;
"S \NAC"
BN"4"155;
%"TAP"
"1","(-7675,4900)","2","mstr_standard","I84";
;
CDS_LIB"mstr_standard"
BODY_TYPE"PLUMBING"
HDL_TAP"TRUE";
"B \NAC \NWC"7;
"S \NAC"
BN"5"153;
%"TAP"
"1","(-7675,4950)","2","mstr_standard","I85";
;
CDS_LIB"mstr_standard"
BODY_TYPE"PLUMBING"
HDL_TAP"TRUE";
"B \NAC \NWC"7;
"S \NAC"
BN"6"151;
%"TAP"
"1","(-7675,5050)","2","mstr_standard","I86";
;
CDS_LIB"mstr_standard"
BODY_TYPE"PLUMBING"
HDL_TAP"TRUE";
"B \NAC \NWC"6;
"S \NAC"
BN"0"164;
%"TAP"
"1","(-7675,5100)","2","mstr_standard","I87";
;
CDS_LIB"mstr_standard"
BODY_TYPE"PLUMBING"
HDL_TAP"TRUE";
"B \NAC \NWC"6;
"S \NAC"
BN"1"162;
%"TAP"
"1","(-7675,5150)","2","mstr_standard","I88";
;
CDS_LIB"mstr_standard"
BODY_TYPE"PLUMBING"
HDL_TAP"TRUE";
"B \NAC \NWC"6;
"S \NAC"
BN"2"160;
%"TAP"
"1","(-7675,5200)","2","mstr_standard","I89";
;
CDS_LIB"mstr_standard"
BODY_TYPE"PLUMBING"
HDL_TAP"TRUE";
"B \NAC \NWC"6;
"S \NAC"
BN"3"158;
%"VCC_CORE"
"1","(-8450,3375)","0","mstr_symbols","I9";
;
HDL_POWER"P3V3_AUX"
CDS_LIB"mstr_symbols"
VOLTAGE"3.3"
ROOM"PVCCINFAON_CPU1_CTRL";
"A"170;
%"TAP"
"1","(-7675,5250)","2","mstr_standard","I90";
;
CDS_LIB"mstr_standard"
BODY_TYPE"PLUMBING"
HDL_TAP"TRUE";
"B \NAC \NWC"6;
"S \NAC"
BN"4"156;
%"TAP"
"1","(-7675,5300)","2","mstr_standard","I91";
;
CDS_LIB"mstr_standard"
BODY_TYPE"PLUMBING"
HDL_TAP"TRUE";
"B \NAC \NWC"6;
"S \NAC"
BN"5"154;
%"TAP"
"1","(-7675,5350)","2","mstr_standard","I92";
;
CDS_LIB"mstr_standard"
BODY_TYPE"PLUMBING"
HDL_TAP"TRUE";
"B \NAC \NWC"6;
"S \NAC"
BN"6"152;
%"TAP"
"1","(-5975,3800)","0","mstr_standard","I93";
;
CDS_LIB"mstr_standard"
BODY_TYPE"PLUMBING"
HDL_TAP"TRUE";
"B \NAC \NWC"8;
"S \NAC"
BN"0"110;
%"TAP"
"1","(-5975,3900)","0","mstr_standard","I94";
;
CDS_LIB"mstr_standard"
BODY_TYPE"PLUMBING"
HDL_TAP"TRUE";
"B \NAC \NWC"8;
"S \NAC"
BN"2"112;
%"TAP"
"1","(-5975,3850)","0","mstr_standard","I95";
;
CDS_LIB"mstr_standard"
BODY_TYPE"PLUMBING"
HDL_TAP"TRUE";
"B \NAC \NWC"8;
"S \NAC"
BN"1"111;
%"TAP"
"1","(-5975,3950)","0","mstr_standard","I96";
;
CDS_LIB"mstr_standard"
BODY_TYPE"PLUMBING"
HDL_TAP"TRUE";
"B \NAC \NWC"8;
"S \NAC"
BN"3"113;
%"TAP"
"1","(-5975,4000)","0","mstr_standard","I97";
;
CDS_LIB"mstr_standard"
BODY_TYPE"PLUMBING"
HDL_TAP"TRUE";
"B \NAC \NWC"8;
"S \NAC"
BN"4"114;
%"TAP"
"1","(-5975,4050)","0","mstr_standard","I98";
;
CDS_LIB"mstr_standard"
BODY_TYPE"PLUMBING"
HDL_TAP"TRUE";
"B \NAC \NWC"8;
"S \NAC"
BN"5"115;
%"TAP"
"1","(-5975,4100)","0","mstr_standard","I99";
;
CDS_LIB"mstr_standard"
BODY_TYPE"PLUMBING"
HDL_TAP"TRUE";
"B \NAC \NWC"8;
"S \NAC"
BN"6"116;
END.
